# BASEBOARD_FAB2 (Tioga Pass) — schematic netlist excerpt (pin names and nets, part order shuffled) for the footprints in the layout excerpt that follows; sources: Cadence DE-HDL packaged netlist, KiCad conversion of Wiwynn_Tioga_Pass_MB.brd

R6W9  RES  4.75K 1% EMPTY  pkg 0402  page 247 : A = PCA9555_A0 ; B = GND
C2M24  CAP_A  0.1UF 16V 10% X7R  pkg 0402V  page 139 : A = PE_PCH_SPRV_TX_DN ; B = PE_PCH_SPRV_TX_C_DN
C3N8  CAP  0.22UF 16V 10% X7R  pkg 0402  page 129 : A = DMI_CPU0_PCH_RX_DP<3> ; B = DMI_CPU0_PCH_RX_C_DP<3>

(kicad_pcb
	(version 20260206)
	(generator "pcbnew")
	(generator_version "10.0")
	(general
		(thickness 1.6)
		(legacy_teardrops no)
	)
	(paper "A4")
	(title_block
		(title "Wiwynn_Tioga_Pass_MB.brd")
		(comment 1 "Tioga Pass / footprints 4194-4196 of 4770")
	)
	(layers
		(0 "F.Cu" signal "TOP")
		(4 "In1.Cu" signal "L2GND")
		(6 "In2.Cu" signal "L3")
		(8 "In3.Cu" signal "L4GND")
		(10 "In4.Cu" signal "L5")
		(12 "In5.Cu" signal "L6GND")
		(14 "In6.Cu" signal "L7VCC")
		(16 "In7.Cu" signal "L8VCC")
		(18 "In8.Cu" signal "L9GND")
		(20 "In9.Cu" signal "L10")
		(22 "In10.Cu" signal "L11GND")
		(24 "In11.Cu" signal "L12")
		(26 "In12.Cu" signal "L13GND")
		(2 "B.Cu" signal "BOTTOM")
		(9 "F.Adhes" user "F.Adhesive")
		(11 "B.Adhes" user "B.Adhesive")
		(13 "F.Paste" user "Package Geometry/Pastemask Top")
		(15 "B.Paste" user "Package Geometry/Pastemask Bottom")
		(5 "F.SilkS" user "Ref Des/Silkscreen Top")
		(7 "B.SilkS" user "Ref Des/Silkscreen Bottom")
		(1 "F.Mask" user "Board Geometry/Soldermask Top")
		(3 "B.Mask" user "Board Geometry/Soldermask Bottom")
		(17 "Dwgs.User" user "User.Drawings")
		(19 "Cmts.User" user "User.Comments")
		(21 "Eco1.User" user "User.Eco1")
		(23 "Eco2.User" user "User.Eco2")
		(25 "Edge.Cuts" user "Board Geometry/Outline")
		(27 "Margin" user)
		(31 "F.CrtYd" user "Package Geometry/Place Bound Top")
		(29 "B.CrtYd" user "Package Geometry/Place Bound Bottom")
		(35 "F.Fab" user "Ref Des/Assembly Top")
		(33 "B.Fab" user "Ref Des/Assembly Bottom")
	)
	(footprint ""
		(layer "B.Cu")
		(at 476.936816 -145.470372 180)
		(property "Reference" "R6W9"
			(at 0.8382 -0.67818 180)
			(unlocked yes)
			(layer "B.SilkS")
			(effects
				(font
					(size 0.4064 0.254)
					(thickness 0.1524)
				)
				(justify left mirror)
			)
		)
		(property "Value" ""
			(at 0 0 0)
			(layer "B.Fab")
			(effects
				(font
					(size 1.27 1.27)
				)
				(justify mirror)
			)
		)
		(duplicate_pad_numbers_are_jumpers no)
		(fp_poly
			(pts
				(xy 0.2794 -0.1016) (xy -0.2794 -0.1016) (xy -0.2794 0.9906) (xy 0.2794 0.9906)
			)
			(stroke
				(width 0)
				(type default)
			)
			(fill no)
			(layer "B.CrtYd")
		)
		(fp_line
			(start 0.2794 0.9906)
			(end -0.2794 0.9906)
			(stroke
				(width 0.1)
				(type default)
			)
			(layer "B.Fab")
		)
		(fp_line
			(start 0.2794 -0.1016)
			(end 0.2794 0.9906)
			(stroke
				(width 0.1)
				(type default)
			)
			(layer "B.Fab")
		)
		(fp_line
			(start -0.2794 0.9906)
			(end -0.2794 -0.1016)
			(stroke
				(width 0.1)
				(type default)
			)
			(layer "B.Fab")
		)
		(fp_line
			(start -0.2794 -0.1016)
			(end 0.2794 -0.1016)
			(stroke
				(width 0.1)
				(type default)
			)
			(layer "B.Fab")
		)
		(pad "1" smd rect
			(at 0 0)
			(size 0.508 0.508)
			(layers "B.Cu" "B.Mask" "B.Paste")
			(net "PCA9555_A0")
		)
		(pad "2" smd rect
			(at 0 0.889)
			(size 0.508 0.508)
			(layers "B.Cu" "B.Mask" "B.Paste")
			(net "GND")
		)
		(zone
			(layer "B.Cu")
			(hatch none 0.5)
			(connect_pads
				(clearance 0)
			)
			(min_thickness 0.25)
			(keepout
				(tracks not_allowed)
				(vias allowed)
				(pads allowed)
				(copperpour not_allowed)
				(footprints allowed)
			)
			(placement
				(enabled no)
				(sheetname "")
			)
			(fill
				(thermal_gap 0.5)
				(thermal_bridge_width 0.5)
				(island_removal_mode 0)
			)
			(polygon
				(pts
					(xy 476.682816 -146.105372) (xy 477.190816 -146.105372) (xy 477.190816 -145.724372) (xy 476.682816 -145.724372)
				)
			)
		)
		(zone
			(layer "B.Cu")
			(hatch none 0.5)
			(connect_pads
				(clearance 0)
			)
			(min_thickness 0.25)
			(keepout
				(tracks allowed)
				(vias not_allowed)
				(pads allowed)
				(copperpour not_allowed)
				(footprints allowed)
			)
			(placement
				(enabled no)
				(sheetname "")
			)
			(fill
				(thermal_gap 0.5)
				(thermal_bridge_width 0.5)
				(island_removal_mode 0)
			)
			(polygon
				(pts
					(xy 476.682816 -145.724372) (xy 477.190816 -145.724372) (xy 477.190816 -146.105372) (xy 476.682816 -146.105372)
				)
			)
		)
	)
	(footprint ""
		(layer "B.Cu")
		(at 369.443 -110.998 -90)
		(property "Reference" "C3N8"
			(at 0 0 90)
			(layer "B.SilkS")
			(hide yes)
			(effects
				(font
					(size 1.27 1.27)
				)
				(justify mirror)
			)
		)
		(property "Value" ""
			(at 0 0 90)
			(layer "B.Fab")
			(effects
				(font
					(size 1.27 1.27)
				)
				(justify mirror)
			)
		)
		(duplicate_pad_numbers_are_jumpers no)
		(fp_poly
			(pts
				(xy -0.3048 -0.1016) (xy -0.3048 0.9906) (xy 0.3048 0.9906) (xy 0.3048 -0.1016)
			)
			(stroke
				(width 0)
				(type default)
			)
			(fill no)
			(layer "B.CrtYd")
		)
		(fp_line
			(start -0.3048 0.9906)
			(end -0.3048 -0.1016)
			(stroke
				(width 0.1)
				(type default)
			)
			(layer "B.Fab")
		)
		(fp_line
			(start 0.3048 0.9906)
			(end -0.3048 0.9906)
			(stroke
				(width 0.1)
				(type default)
			)
			(layer "B.Fab")
		)
		(fp_line
			(start -0.3048 -0.1016)
			(end 0.3048 -0.1016)
			(stroke
				(width 0.1)
				(type default)
			)
			(layer "B.Fab")
		)
		(fp_line
			(start 0.3048 -0.1016)
			(end 0.3048 0.9906)
			(stroke
				(width 0.1)
				(type default)
			)
			(layer "B.Fab")
		)
		(pad "1" smd rect
			(at 0 0 90)
			(size 0.508 0.508)
			(layers "B.Cu" "B.Mask" "B.Paste")
			(net "DMI_CPU0_PCH_RX_DP<3>")
		)
		(pad "2" smd rect
			(at 0 0.889 90)
			(size 0.508 0.508)
			(layers "B.Cu" "B.Mask" "B.Paste")
			(net "DMI_CPU0_PCH_RX_C_DP<3>")
		)
		(zone
			(layer "B.Cu")
			(hatch none 0.5)
			(connect_pads
				(clearance 0)
			)
			(min_thickness 0.25)
			(keepout
				(tracks not_allowed)
				(vias allowed)
				(pads allowed)
				(copperpour not_allowed)
				(footprints allowed)
			)
			(placement
				(enabled no)
				(sheetname "")
			)
			(fill
				(thermal_gap 0.5)
				(thermal_bridge_width 0.5)
				(island_removal_mode 0)
			)
			(polygon
				(pts
					(xy 368.808 -110.744) (xy 368.808 -111.252) (xy 369.189 -111.252) (xy 369.189 -110.744)
				)
			)
		)
		(zone
			(layer "B.Cu")
			(hatch none 0.5)
			(connect_pads
				(clearance 0)
			)
			(min_thickness 0.25)
			(keepout
				(tracks allowed)
				(vias not_allowed)
				(pads allowed)
				(copperpour not_allowed)
				(footprints allowed)
			)
			(placement
				(enabled no)
				(sheetname "")
			)
			(fill
				(thermal_gap 0.5)
				(thermal_bridge_width 0.5)
				(island_removal_mode 0)
			)
			(polygon
				(pts
					(xy 369.189 -110.744) (xy 369.189 -111.252) (xy 368.808 -111.252) (xy 368.808 -110.744)
				)
			)
		)
	)
	(footprint ""
		(layer "B.Cu")
		(at 401.25777 -126.389384 90)
		(property "Reference" "C2M24"
			(at 0 0 90)
			(layer "B.SilkS")
			(hide yes)
			(effects
				(font
					(size 1.27 1.27)
				)
				(justify mirror)
			)
		)
		(property "Value" ""
			(at 0 0 90)
			(layer "B.Fab")
			(effects
				(font
					(size 1.27 1.27)
				)
				(justify mirror)
			)
		)
		(duplicate_pad_numbers_are_jumpers no)
		(fp_poly
			(pts
				(xy -0.3048 -0.1016) (xy -0.3048 0.9906) (xy 0.3048 0.9906) (xy 0.3048 -0.1016)
			)
			(stroke
				(width 0)
				(type default)
			)
			(fill no)
			(layer "B.CrtYd")
		)
		(fp_line
			(start 0.3048 -0.1016)
			(end 0.3048 0.9906)
			(stroke
				(width 0.1)
				(type default)
			)
			(layer "B.Fab")
		)
		(fp_line
			(start -0.3048 -0.1016)
			(end 0.3048 -0.1016)
			(stroke
				(width 0.1)
				(type default)
			)
			(layer "B.Fab")
		)
		(fp_line
			(start 0.3048 0.9906)
			(end -0.3048 0.9906)
			(stroke
				(width 0.1)
				(type default)
			)
			(layer "B.Fab")
		)
		(fp_line
			(start -0.3048 0.9906)
			(end -0.3048 -0.1016)
			(stroke
				(width 0.1)
				(type default)
			)
			(layer "B.Fab")
		)
		(pad "1" smd rect
			(at 0 0 270)
			(size 0.508 0.508)
			(layers "B.Cu" "B.Mask" "B.Paste")
			(net "PE_PCH_SPRV_TX_DN")
		)
		(pad "2" smd rect
			(at 0 0.889 270)
			(size 0.508 0.508)
			(layers "B.Cu" "B.Mask" "B.Paste")
			(net "PE_PCH_SPRV_TX_C_DN")
		)
		(zone
			(layer "B.Cu")
			(hatch none 0.5)
			(connect_pads
				(clearance 0)
			)
			(min_thickness 0.25)
			(keepout
				(tracks allowed)
				(vias not_allowed)
				(pads allowed)
				(copperpour not_allowed)
				(footprints allowed)
			)
			(placement
				(enabled no)
				(sheetname "")
			)
			(fill
				(thermal_gap 0.5)
				(thermal_bridge_width 0.5)
				(island_removal_mode 0)
			)
			(polygon
				(pts
					(xy 401.51177 -126.643384) (xy 401.51177 -126.135384) (xy 401.89277 -126.135384) (xy 401.89277 -126.643384)
				)
			)
		)
		(zone
			(layer "B.Cu")
			(hatch none 0.5)
			(connect_pads
				(clearance 0)
			)
			(min_thickness 0.25)
			(keepout
				(tracks not_allowed)
				(vias allowed)
				(pads allowed)
				(copperpour not_allowed)
				(footprints allowed)
			)
			(placement
				(enabled no)
				(sheetname "")
			)
			(fill
				(thermal_gap 0.5)
				(thermal_bridge_width 0.5)
				(island_removal_mode 0)
			)
			(polygon
				(pts
					(xy 401.89277 -126.643384) (xy 401.89277 -126.135384) (xy 401.51177 -126.135384) (xy 401.51177 -126.643384)
				)
			)
		)
	)
)
